FILE_TYPE=LIBRARY_PARTS;
primitive 'PCA9617ADP';
  pin
    'EN':
      PIN_NUMBER='(5)';
      INPUT_LOAD='(-0.01,0.01)';
    'VCCA':
      PIN_NUMBER='(1)';
      PINUSE='POWER';
      NO_LOAD_CHECK='Both';
      NO_IO_CHECK='Both';
      NO_ASSERT_CHECK='TRUE';
      NO_DIR_CHECK='TRUE';
      ALLOW_CONNECT='TRUE';
    'VCCB':
      PIN_NUMBER='(8)';
      PINUSE='POWER';
      NO_LOAD_CHECK='Both';
      NO_IO_CHECK='Both';
      NO_ASSERT_CHECK='TRUE';
      NO_DIR_CHECK='TRUE';
      ALLOW_CONNECT='TRUE';
    'SCLA':
      PIN_NUMBER='(2)';
      BIDIRECTIONAL='TRUE';
      INPUT_LOAD='(-0.01,0.01)';
      OUTPUT_LOAD='(1.0,-1.0)';
    'SDAA':
      PIN_NUMBER='(3)';
      BIDIRECTIONAL='TRUE';
      INPUT_LOAD='(-0.01,0.01)';
      OUTPUT_LOAD='(1.0,-1.0)';
    'SDAB':
      PIN_NUMBER='(6)';
      BIDIRECTIONAL='TRUE';
      INPUT_LOAD='(-0.01,0.01)';
      OUTPUT_LOAD='(1.0,-1.0)';
    'SCLB':
      PIN_NUMBER='(7)';
      BIDIRECTIONAL='TRUE';
      INPUT_LOAD='(-0.01,0.01)';
      OUTPUT_LOAD='(1.0,-1.0)';
    'GND':
      PIN_NUMBER='(4)';
      PINUSE='POWER';
      NO_LOAD_CHECK='Both';
      NO_IO_CHECK='Both';
      NO_ASSERT_CHECK='TRUE';
      NO_DIR_CHECK='TRUE';
      ALLOW_CONNECT='TRUE';
  end_pin;
  body
    PART_NAME='PCA9617ADP';
    BODY_NAME='PCA9617ADP';
    PHYS_DES_PREFIX='U';
    CLASS='IC';
  end_body;
end_primitive;

END.
